(kicad_pcb
	(version 20260206)
	(generator "pcbnew")
	(generator_version "10.0")
	(general
		(thickness 1.6)
		(legacy_teardrops no)
	)
	(paper "A4")
	(title_block
		(title "03242023_DA0F0TMBIJ0_F0T_Motherboard_J_brd_V01_OCP.brd")
		(comment 1 "Grand Teton / footprint 652 of 6105 (J8), pads 113-224 of 291")
	)
	(layers
		(0 "F.Cu" signal "TOP")
		(4 "In1.Cu" signal "GND")
		(6 "In2.Cu" signal "IN1")
		(8 "In3.Cu" signal "GND1")
		(10 "In4.Cu" signal "IN2")
		(12 "In5.Cu" signal "GND2")
		(14 "In6.Cu" signal "IN3")
		(16 "In7.Cu" signal "GND3")
		(18 "In8.Cu" signal "VCC")
		(20 "In9.Cu" signal "VCC1")
		(22 "In10.Cu" signal "GND4")
		(24 "In11.Cu" signal "IN4")
		(26 "In12.Cu" signal "GND5")
		(28 "In13.Cu" signal "IN5")
		(30 "In14.Cu" signal "GND6")
		(32 "In15.Cu" signal "IN6")
		(34 "In16.Cu" signal "GND7")
		(2 "B.Cu" signal "BOTTOM")
		(9 "F.Adhes" user "F.Adhesive")
		(11 "B.Adhes" user "B.Adhesive")
		(13 "F.Paste" user "Package Geometry/Pastemask Top")
		(15 "B.Paste" user "Package Geometry/Pastemask Bottom")
		(5 "F.SilkS" user "Ref Des/Silkscreen Top")
		(7 "B.SilkS" user "Ref Des/Silkscreen Bottom")
		(1 "F.Mask" user "Board Geometry/Soldermask Top")
		(3 "B.Mask" user "Board Geometry/Soldermask Bottom")
		(17 "Dwgs.User" user "User.Drawings")
		(19 "Cmts.User" user "User.Comments")
		(21 "Eco1.User" user "User.Eco1")
		(23 "Eco2.User" user "User.Eco2")
		(25 "Edge.Cuts" user "Board Geometry/Outline")
		(27 "Margin" user)
		(31 "F.CrtYd" user "Package Geometry/Place Bound Top")
		(29 "B.CrtYd" user "Package Geometry/Place Bound Bottom")
		(35 "F.Fab" user "Ref Des/Assembly Top")
		(33 "B.Fab" user "Ref Des/Assembly Bottom")
	)
	(footprint ""
		(layer "F.Cu")
		(at 265.674348 -258.091686)
		(property "Reference" "J8"
			(at -3.683 -81.702148 0)
			(unlocked yes)
			(layer "F.SilkS")
			(effects
				(font
					(size 0.7874 0.5842)
					(thickness 0.1524)
				)
				(justify left)
			)
		)
		(property "Value" ""
			(at 0 0 0)
			(layer "F.Fab")
			(effects
				(font
					(size 1.27 1.27)
				)
			)
		)
		(duplicate_pad_numbers_are_jumpers no)
		(pad "113" smd rect
			(at -2.050034 36.975034 270)
			(size 0.519938 1.4986)
			(layers "F.Cu" "F.Mask" "F.Paste")
			(net "M_D_CPU0_SB_DQ<9>")
		)
		(pad "114" smd rect
			(at -2.050034 37.824918 270)
			(size 0.519938 1.4986)
			(layers "F.Cu" "F.Mask" "F.Paste")
			(net "GND")
		)
		(pad "115" smd rect
			(at -2.050034 38.675056 270)
			(size 0.519938 1.4986)
			(layers "F.Cu" "F.Mask" "F.Paste")
			(net "M_D_CPU0_SB_DQS_DP<1>")
		)
		(pad "116" smd rect
			(at -2.050034 39.52494 270)
			(size 0.519938 1.4986)
			(layers "F.Cu" "F.Mask" "F.Paste")
			(net "M_D_CPU0_SB_DQS_DN<1>")
		)
		(pad "117" smd rect
			(at -2.050034 40.375078 270)
			(size 0.519938 1.4986)
			(layers "F.Cu" "F.Mask" "F.Paste")
			(net "GND")
		)
		(pad "118" smd rect
			(at -2.050034 41.224962 270)
			(size 0.519938 1.4986)
			(layers "F.Cu" "F.Mask" "F.Paste")
			(net "M_D_CPU0_SB_DQ<12>")
		)
		(pad "119" smd rect
			(at -2.050034 42.0751 270)
			(size 0.519938 1.4986)
			(layers "F.Cu" "F.Mask" "F.Paste")
			(net "GND")
		)
		(pad "120" smd rect
			(at -2.050034 42.924984 270)
			(size 0.519938 1.4986)
			(layers "F.Cu" "F.Mask" "F.Paste")
			(net "M_D_CPU0_SB_DQ<13>")
		)
		(pad "121" smd rect
			(at -2.050034 43.775122 270)
			(size 0.519938 1.4986)
			(layers "F.Cu" "F.Mask" "F.Paste")
			(net "GND")
		)
		(pad "122" smd rect
			(at -2.050034 44.625006 270)
			(size 0.519938 1.4986)
			(layers "F.Cu" "F.Mask" "F.Paste")
			(net "M_D_CPU0_SB_DQ<16>")
		)
		(pad "123" smd rect
			(at -2.050034 45.47489 270)
			(size 0.519938 1.4986)
			(layers "F.Cu" "F.Mask" "F.Paste")
			(net "GND")
		)
		(pad "124" smd rect
			(at -2.050034 46.325028 270)
			(size 0.519938 1.4986)
			(layers "F.Cu" "F.Mask" "F.Paste")
			(net "M_D_CPU0_SB_DQ<17>")
		)
		(pad "125" smd rect
			(at -2.050034 47.174912 270)
			(size 0.519938 1.4986)
			(layers "F.Cu" "F.Mask" "F.Paste")
			(net "GND")
		)
		(pad "126" smd rect
			(at -2.050034 48.02505 270)
			(size 0.519938 1.4986)
			(layers "F.Cu" "F.Mask" "F.Paste")
			(net "M_D_CPU0_SB_DQS_DP<2>")
		)
		(pad "127" smd rect
			(at -2.050034 48.874934 270)
			(size 0.519938 1.4986)
			(layers "F.Cu" "F.Mask" "F.Paste")
			(net "M_D_CPU0_SB_DQS_DN<2>")
		)
		(pad "128" smd rect
			(at -2.050034 49.725072 270)
			(size 0.519938 1.4986)
			(layers "F.Cu" "F.Mask" "F.Paste")
			(net "GND")
		)
		(pad "129" smd rect
			(at -2.050034 50.574956 270)
			(size 0.519938 1.4986)
			(layers "F.Cu" "F.Mask" "F.Paste")
			(net "M_D_CPU0_SB_DQ<20>")
		)
		(pad "130" smd rect
			(at -2.050034 51.425094 270)
			(size 0.519938 1.4986)
			(layers "F.Cu" "F.Mask" "F.Paste")
			(net "GND")
		)
		(pad "131" smd rect
			(at -2.050034 52.274978 270)
			(size 0.519938 1.4986)
			(layers "F.Cu" "F.Mask" "F.Paste")
			(net "M_D_CPU0_SB_DQ<21>")
		)
		(pad "132" smd rect
			(at -2.050034 53.125116 270)
			(size 0.519938 1.4986)
			(layers "F.Cu" "F.Mask" "F.Paste")
			(net "GND")
		)
		(pad "133" smd rect
			(at -2.050034 53.975 270)
			(size 0.519938 1.4986)
			(layers "F.Cu" "F.Mask" "F.Paste")
			(net "M_D_CPU0_SB_DQ<24>")
		)
		(pad "134" smd rect
			(at -2.050034 54.824884 270)
			(size 0.519938 1.4986)
			(layers "F.Cu" "F.Mask" "F.Paste")
			(net "GND")
		)
		(pad "135" smd rect
			(at -2.050034 55.675022 270)
			(size 0.519938 1.4986)
			(layers "F.Cu" "F.Mask" "F.Paste")
			(net "M_D_CPU0_SB_DQ<25>")
		)
		(pad "136" smd rect
			(at -2.050034 56.524906 270)
			(size 0.519938 1.4986)
			(layers "F.Cu" "F.Mask" "F.Paste")
			(net "GND")
		)
		(pad "137" smd rect
			(at -2.050034 57.375044 270)
			(size 0.519938 1.4986)
			(layers "F.Cu" "F.Mask" "F.Paste")
			(net "M_D_CPU0_SB_DQS_DP<3>")
		)
		(pad "138" smd rect
			(at -2.050034 58.224928 270)
			(size 0.519938 1.4986)
			(layers "F.Cu" "F.Mask" "F.Paste")
			(net "M_D_CPU0_SB_DQS_DN<3>")
		)
		(pad "139" smd rect
			(at -2.050034 59.075066 270)
			(size 0.519938 1.4986)
			(layers "F.Cu" "F.Mask" "F.Paste")
			(net "GND")
		)
		(pad "140" smd rect
			(at -2.050034 59.92495 270)
			(size 0.519938 1.4986)
			(layers "F.Cu" "F.Mask" "F.Paste")
			(net "M_D_CPU0_SB_DQ<28>")
		)
		(pad "141" smd rect
			(at -2.050034 60.775088 270)
			(size 0.519938 1.4986)
			(layers "F.Cu" "F.Mask" "F.Paste")
			(net "GND")
		)
		(pad "142" smd rect
			(at -2.050034 61.624972 270)
			(size 0.519938 1.4986)
			(layers "F.Cu" "F.Mask" "F.Paste")
			(net "M_D_CPU0_SB_DQ<29>")
		)
		(pad "143" smd rect
			(at -2.050034 62.47511 270)
			(size 0.519938 1.4986)
			(layers "F.Cu" "F.Mask" "F.Paste")
			(net "GND")
		)
		(pad "144" smd rect
			(at -2.050034 63.324994 270)
			(size 0.519938 1.4986)
			(layers "F.Cu" "F.Mask" "F.Paste")
			(net "TP_CHD_CPU0_DIMM2_FRU_1")
		)
		(pad "145" smd rect
			(at 2.050034 -63.324994 270)
			(size 0.519938 1.4986)
			(layers "F.Cu" "F.Mask" "F.Paste")
			(net "P12V_S3_AUX_CPU0_NVDIMM")
		)
		(pad "146" smd rect
			(at 2.050034 -62.47511 270)
			(size 0.519938 1.4986)
			(layers "F.Cu" "F.Mask" "F.Paste")
			(net "P12V_S3_AUX_CPU0_NVDIMM")
		)
		(pad "147" smd rect
			(at 2.050034 -61.624972 270)
			(size 0.519938 1.4986)
			(layers "F.Cu" "F.Mask" "F.Paste")
			(net "PWRGD_CHD_CPU0_DIMM2")
		)
		(pad "148" smd rect
			(at 2.050034 -60.775088 270)
			(size 0.519938 1.4986)
			(layers "F.Cu" "F.Mask" "F.Paste")
			(net "PD_CHD_CPU0_DIMM2_SAA")
		)
		(pad "149" smd rect
			(at 2.050034 -59.92495 270)
			(size 0.519938 1.4986)
			(layers "F.Cu" "F.Mask" "F.Paste")
			(net "TP_CHD_CPU0_DIMM2_FRU_2")
		)
		(pad "150" smd rect
			(at 2.050034 -59.075066 270)
			(size 0.519938 1.4986)
			(layers "F.Cu" "F.Mask" "F.Paste")
			(net "TP_CHD_CPU0_DIMM2_FRU_3")
		)
		(pad "151" smd rect
			(at 2.050034 -58.224928 270)
			(size 0.519938 1.4986)
			(layers "F.Cu" "F.Mask" "F.Paste")
			(net "GND")
		)
		(pad "152" smd rect
			(at 2.050034 -57.375044 270)
			(size 0.519938 1.4986)
			(layers "F.Cu" "F.Mask" "F.Paste")
			(net "M_D_CPU0_SA_DQ<2>")
		)
		(pad "153" smd rect
			(at 2.050034 -56.524906 270)
			(size 0.519938 1.4986)
			(layers "F.Cu" "F.Mask" "F.Paste")
			(net "GND")
		)
		(pad "154" smd rect
			(at 2.050034 -55.675022 270)
			(size 0.519938 1.4986)
			(layers "F.Cu" "F.Mask" "F.Paste")
			(net "M_D_CPU0_SA_DQ<3>")
		)
		(pad "155" smd rect
			(at 2.050034 -54.824884 270)
			(size 0.519938 1.4986)
			(layers "F.Cu" "F.Mask" "F.Paste")
			(net "GND")
		)
		(pad "156" smd rect
			(at 2.050034 -53.975 270)
			(size 0.519938 1.4986)
			(layers "F.Cu" "F.Mask" "F.Paste")
			(net "M_D_CPU0_SA_DQS_DN<5>")
		)
		(pad "157" smd rect
			(at 2.050034 -53.125116 270)
			(size 0.519938 1.4986)
			(layers "F.Cu" "F.Mask" "F.Paste")
			(net "M_D_CPU0_SA_DQS_DP<5>")
		)
		(pad "158" smd rect
			(at 2.050034 -52.274978 270)
			(size 0.519938 1.4986)
			(layers "F.Cu" "F.Mask" "F.Paste")
			(net "GND")
		)
		(pad "159" smd rect
			(at 2.050034 -51.425094 270)
			(size 0.519938 1.4986)
			(layers "F.Cu" "F.Mask" "F.Paste")
			(net "M_D_CPU0_SA_DQ<6>")
		)
		(pad "160" smd rect
			(at 2.050034 -50.574956 270)
			(size 0.519938 1.4986)
			(layers "F.Cu" "F.Mask" "F.Paste")
			(net "GND")
		)
		(pad "161" smd rect
			(at 2.050034 -49.725072 270)
			(size 0.519938 1.4986)
			(layers "F.Cu" "F.Mask" "F.Paste")
			(net "M_D_CPU0_SA_DQ<7>")
		)
		(pad "162" smd rect
			(at 2.050034 -48.874934 270)
			(size 0.519938 1.4986)
			(layers "F.Cu" "F.Mask" "F.Paste")
			(net "GND")
		)
		(pad "163" smd rect
			(at 2.050034 -48.02505 270)
			(size 0.519938 1.4986)
			(layers "F.Cu" "F.Mask" "F.Paste")
			(net "M_D_CPU0_SA_DQ<10>")
		)
		(pad "164" smd rect
			(at 2.050034 -47.174912 270)
			(size 0.519938 1.4986)
			(layers "F.Cu" "F.Mask" "F.Paste")
			(net "GND")
		)
		(pad "165" smd rect
			(at 2.050034 -46.325028 270)
			(size 0.519938 1.4986)
			(layers "F.Cu" "F.Mask" "F.Paste")
			(net "M_D_CPU0_SA_DQ<11>")
		)
		(pad "166" smd rect
			(at 2.050034 -45.47489 270)
			(size 0.519938 1.4986)
			(layers "F.Cu" "F.Mask" "F.Paste")
			(net "GND")
		)
		(pad "167" smd rect
			(at 2.050034 -44.625006 270)
			(size 0.519938 1.4986)
			(layers "F.Cu" "F.Mask" "F.Paste")
			(net "M_D_CPU0_SA_DQS_DN<6>")
		)
		(pad "168" smd rect
			(at 2.050034 -43.775122 270)
			(size 0.519938 1.4986)
			(layers "F.Cu" "F.Mask" "F.Paste")
			(net "M_D_CPU0_SA_DQS_DP<6>")
		)
		(pad "169" smd rect
			(at 2.050034 -42.924984 270)
			(size 0.519938 1.4986)
			(layers "F.Cu" "F.Mask" "F.Paste")
			(net "GND")
		)
		(pad "170" smd rect
			(at 2.050034 -42.0751 270)
			(size 0.519938 1.4986)
			(layers "F.Cu" "F.Mask" "F.Paste")
			(net "M_D_CPU0_SA_DQ<14>")
		)
		(pad "171" smd rect
			(at 2.050034 -41.224962 270)
			(size 0.519938 1.4986)
			(layers "F.Cu" "F.Mask" "F.Paste")
			(net "GND")
		)
		(pad "172" smd rect
			(at 2.050034 -40.375078 270)
			(size 0.519938 1.4986)
			(layers "F.Cu" "F.Mask" "F.Paste")
			(net "M_D_CPU0_SA_DQ<15>")
		)
		(pad "173" smd rect
			(at 2.050034 -39.52494 270)
			(size 0.519938 1.4986)
			(layers "F.Cu" "F.Mask" "F.Paste")
			(net "GND")
		)
		(pad "174" smd rect
			(at 2.050034 -38.675056 270)
			(size 0.519938 1.4986)
			(layers "F.Cu" "F.Mask" "F.Paste")
			(net "M_D_CPU0_SA_DQ<18>")
		)
		(pad "175" smd rect
			(at 2.050034 -37.824918 270)
			(size 0.519938 1.4986)
			(layers "F.Cu" "F.Mask" "F.Paste")
			(net "GND")
		)
		(pad "176" smd rect
			(at 2.050034 -36.975034 270)
			(size 0.519938 1.4986)
			(layers "F.Cu" "F.Mask" "F.Paste")
			(net "M_D_CPU0_SA_DQ<19>")
		)
		(pad "177" smd rect
			(at 2.050034 -36.124896 270)
			(size 0.519938 1.4986)
			(layers "F.Cu" "F.Mask" "F.Paste")
			(net "GND")
		)
		(pad "178" smd rect
			(at 2.050034 -35.275012 270)
			(size 0.519938 1.4986)
			(layers "F.Cu" "F.Mask" "F.Paste")
			(net "M_D_CPU0_SA_DQS_DN<7>")
		)
		(pad "179" smd rect
			(at 2.050034 -34.425128 270)
			(size 0.519938 1.4986)
			(layers "F.Cu" "F.Mask" "F.Paste")
			(net "M_D_CPU0_SA_DQS_DP<7>")
		)
		(pad "180" smd rect
			(at 2.050034 -33.57499 270)
			(size 0.519938 1.4986)
			(layers "F.Cu" "F.Mask" "F.Paste")
			(net "GND")
		)
		(pad "181" smd rect
			(at 2.050034 -32.725106 270)
			(size 0.519938 1.4986)
			(layers "F.Cu" "F.Mask" "F.Paste")
			(net "M_D_CPU0_SA_DQ<22>")
		)
		(pad "182" smd rect
			(at 2.050034 -31.874968 270)
			(size 0.519938 1.4986)
			(layers "F.Cu" "F.Mask" "F.Paste")
			(net "GND")
		)
		(pad "183" smd rect
			(at 2.050034 -31.025084 270)
			(size 0.519938 1.4986)
			(layers "F.Cu" "F.Mask" "F.Paste")
			(net "M_D_CPU0_SA_DQ<23>")
		)
		(pad "184" smd rect
			(at 2.050034 -30.174946 270)
			(size 0.519938 1.4986)
			(layers "F.Cu" "F.Mask" "F.Paste")
			(net "GND")
		)
		(pad "185" smd rect
			(at 2.050034 -29.325062 270)
			(size 0.519938 1.4986)
			(layers "F.Cu" "F.Mask" "F.Paste")
			(net "M_D_CPU0_SA_DQ<26>")
		)
		(pad "186" smd rect
			(at 2.050034 -28.474924 270)
			(size 0.519938 1.4986)
			(layers "F.Cu" "F.Mask" "F.Paste")
			(net "GND")
		)
		(pad "187" smd rect
			(at 2.050034 -27.62504 270)
			(size 0.519938 1.4986)
			(layers "F.Cu" "F.Mask" "F.Paste")
			(net "M_D_CPU0_SA_DQ<27>")
		)
		(pad "188" smd rect
			(at 2.050034 -26.774902 270)
			(size 0.519938 1.4986)
			(layers "F.Cu" "F.Mask" "F.Paste")
			(net "GND")
		)
		(pad "189" smd rect
			(at 2.050034 -25.925018 270)
			(size 0.519938 1.4986)
			(layers "F.Cu" "F.Mask" "F.Paste")
			(net "M_D_CPU0_SA_DQS_DN<8>")
		)
		(pad "190" smd rect
			(at 2.050034 -25.07488 270)
			(size 0.519938 1.4986)
			(layers "F.Cu" "F.Mask" "F.Paste")
			(net "M_D_CPU0_SA_DQS_DP<8>")
		)
		(pad "191" smd rect
			(at 2.050034 -24.224996 270)
			(size 0.519938 1.4986)
			(layers "F.Cu" "F.Mask" "F.Paste")
			(net "GND")
		)
		(pad "192" smd rect
			(at 2.050034 -23.375112 270)
			(size 0.519938 1.4986)
			(layers "F.Cu" "F.Mask" "F.Paste")
			(net "M_D_CPU0_SA_DQ<30>")
		)
		(pad "193" smd rect
			(at 2.050034 -22.524974 270)
			(size 0.519938 1.4986)
			(layers "F.Cu" "F.Mask" "F.Paste")
			(net "GND")
		)
		(pad "194" smd rect
			(at 2.050034 -21.67509 270)
			(size 0.519938 1.4986)
			(layers "F.Cu" "F.Mask" "F.Paste")
			(net "M_D_CPU0_SA_DQ<31>")
		)
		(pad "195" smd rect
			(at 2.050034 -20.824952 270)
			(size 0.519938 1.4986)
			(layers "F.Cu" "F.Mask" "F.Paste")
			(net "GND")
		)
		(pad "196" smd rect
			(at 2.050034 -19.975068 270)
			(size 0.519938 1.4986)
			(layers "F.Cu" "F.Mask" "F.Paste")
			(net "M_D_CPU0_SA_CB<2>")
		)
		(pad "197" smd rect
			(at 2.050034 -19.12493 270)
			(size 0.519938 1.4986)
			(layers "F.Cu" "F.Mask" "F.Paste")
			(net "GND")
		)
		(pad "198" smd rect
			(at 2.050034 -18.275046 270)
			(size 0.519938 1.4986)
			(layers "F.Cu" "F.Mask" "F.Paste")
			(net "M_D_CPU0_SA_CB<3>")
		)
		(pad "199" smd rect
			(at 2.050034 -17.424908 270)
			(size 0.519938 1.4986)
			(layers "F.Cu" "F.Mask" "F.Paste")
			(net "GND")
		)
		(pad "200" smd rect
			(at 2.050034 -16.575024 270)
			(size 0.519938 1.4986)
			(layers "F.Cu" "F.Mask" "F.Paste")
			(net "M_D_CPU0_SA_DQS_DN<9>")
		)
		(pad "201" smd rect
			(at 2.050034 -15.724886 270)
			(size 0.519938 1.4986)
			(layers "F.Cu" "F.Mask" "F.Paste")
			(net "M_D_CPU0_SA_DQS_DP<9>")
		)
		(pad "202" smd rect
			(at 2.050034 -14.875002 270)
			(size 0.519938 1.4986)
			(layers "F.Cu" "F.Mask" "F.Paste")
			(net "GND")
		)
		(pad "203" smd rect
			(at 2.050034 -14.025118 270)
			(size 0.519938 1.4986)
			(layers "F.Cu" "F.Mask" "F.Paste")
			(net "M_D_CPU0_SA_CB<6>")
		)
		(pad "204" smd rect
			(at 2.050034 -13.17498 270)
			(size 0.519938 1.4986)
			(layers "F.Cu" "F.Mask" "F.Paste")
			(net "GND")
		)
		(pad "205" smd rect
			(at 2.050034 -12.325096 270)
			(size 0.519938 1.4986)
			(layers "F.Cu" "F.Mask" "F.Paste")
			(net "M_D_CPU0_SA_CB<7>")
		)
		(pad "206" smd rect
			(at 2.050034 -11.474958 270)
			(size 0.519938 1.4986)
			(layers "F.Cu" "F.Mask" "F.Paste")
			(net "GND")
		)
		(pad "207" smd rect
			(at 2.050034 -10.625074 270)
			(size 0.519938 1.4986)
			(layers "F.Cu" "F.Mask" "F.Paste")
			(net "RST_M_CD_CPU0_FPGA_N")
		)
		(pad "208" smd rect
			(at 2.050034 -9.774936 270)
			(size 0.519938 1.4986)
			(layers "F.Cu" "F.Mask" "F.Paste")
			(net "GND")
		)
		(pad "209" smd rect
			(at 2.050034 -8.925052 270)
			(size 0.519938 1.4986)
			(layers "F.Cu" "F.Mask" "F.Paste")
			(net "M_D_CPU0_SA_CS_N<3>")
		)
		(pad "210" smd rect
			(at 2.050034 -8.074914 270)
			(size 0.519938 1.4986)
			(layers "F.Cu" "F.Mask" "F.Paste")
			(net "GND")
		)
		(pad "211" smd rect
			(at 2.050034 -7.22503 270)
			(size 0.519938 1.4986)
			(layers "F.Cu" "F.Mask" "F.Paste")
			(net "M_D_CPU0_SA_CA<1>")
		)
		(pad "212" smd rect
			(at 2.050034 -6.374892 270)
			(size 0.519938 1.4986)
			(layers "F.Cu" "F.Mask" "F.Paste")
			(net "GND")
		)
		(pad "213" smd rect
			(at 2.050034 -5.525008 270)
			(size 0.519938 1.4986)
			(layers "F.Cu" "F.Mask" "F.Paste")
			(net "M_D_CPU0_SA_CA<3>")
		)
		(pad "214" smd rect
			(at 2.050034 -4.675124 270)
			(size 0.519938 1.4986)
			(layers "F.Cu" "F.Mask" "F.Paste")
			(net "GND")
		)
		(pad "215" smd rect
			(at 2.050034 -3.824986 270)
			(size 0.519938 1.4986)
			(layers "F.Cu" "F.Mask" "F.Paste")
			(net "M_D_CPU0_SA_CA<5>")
		)
		(pad "216" smd rect
			(at 2.050034 -2.975102 270)
			(size 0.519938 1.4986)
			(layers "F.Cu" "F.Mask" "F.Paste")
			(net "GND")
		)
		(pad "217" smd rect
			(at 2.050034 -2.124964 270)
			(size 0.519938 1.4986)
			(layers "F.Cu" "F.Mask" "F.Paste")
			(net "M_D_CPU0_CLK_DP<1>")
		)
		(pad "218" smd rect
			(at 2.050034 -1.27508 270)
			(size 0.519938 1.4986)
			(layers "F.Cu" "F.Mask" "F.Paste")
			(net "M_D_CPU0_CLK_DN<1>")
		)
		(pad "219" smd rect
			(at 2.050034 -0.424942 270)
			(size 0.519938 1.4986)
			(layers "F.Cu" "F.Mask" "F.Paste")
			(net "GND")
		)
		(pad "220" smd rect
			(at 2.050034 5.525008 270)
			(size 0.519938 1.4986)
			(layers "F.Cu" "F.Mask" "F.Paste")
			(net "TP_CHD_CPU0_DIMM2_FRU_4")
		)
		(pad "221" smd rect
			(at 2.050034 6.374892 270)
			(size 0.519938 1.4986)
			(layers "F.Cu" "F.Mask" "F.Paste")
			(net "M_D_CPU0_SB_CA<1>")
		)
		(pad "222" smd rect
			(at 2.050034 7.22503 270)
			(size 0.519938 1.4986)
			(layers "F.Cu" "F.Mask" "F.Paste")
			(net "GND")
		)
		(pad "223" smd rect
			(at 2.050034 8.074914 270)
			(size 0.519938 1.4986)
			(layers "F.Cu" "F.Mask" "F.Paste")
			(net "M_D_CPU0_SB_CA<3>")
		)
		(pad "224" smd rect
			(at 2.050034 8.925052 270)
			(size 0.519938 1.4986)
			(layers "F.Cu" "F.Mask" "F.Paste")
			(net "GND")
		)
	)
)
